# S9S_MB_2U (Grand Teton) — schematic netlist excerpt (pin names and nets, part order shuffled) for the footprints in the layout excerpt that follows; sources: Cadence DE-HDL packaged netlist, KiCad conversion of 03242023_DA0F0TMBIJ0_F0T_Motherboard_J_brd_V01_OCP.brd

R4565  Q_RES  10K 1% CHIP  pkg 0402LF  page 184 : A = PD_GPP_I_13 ; B = GND
R4092  Q_RES  4.7K 1% CHIP  pkg 0402LF  page 172 : A = P3V3_AUX ; B = OCP_V3_2_P3V3_ADC_ALERT_R
PC2142  Q_CAP  10UF 16V 10% X6S  pkg C0805  page 162 : A = P3V3_OCP_V3_2_R ; B = GND

(kicad_pcb
	(version 20260206)
	(generator "pcbnew")
	(generator_version "10.0")
	(general
		(thickness 1.6)
		(legacy_teardrops no)
	)
	(paper "A4")
	(title_block
		(title "03242023_DA0F0TMBIJ0_F0T_Motherboard_J_brd_V01_OCP.brd")
		(comment 1 "Grand Teton / footprints 491-493 of 6105")
	)
	(layers
		(0 "F.Cu" signal "TOP")
		(4 "In1.Cu" signal "GND")
		(6 "In2.Cu" signal "IN1")
		(8 "In3.Cu" signal "GND1")
		(10 "In4.Cu" signal "IN2")
		(12 "In5.Cu" signal "GND2")
		(14 "In6.Cu" signal "IN3")
		(16 "In7.Cu" signal "GND3")
		(18 "In8.Cu" signal "VCC")
		(20 "In9.Cu" signal "VCC1")
		(22 "In10.Cu" signal "GND4")
		(24 "In11.Cu" signal "IN4")
		(26 "In12.Cu" signal "GND5")
		(28 "In13.Cu" signal "IN5")
		(30 "In14.Cu" signal "GND6")
		(32 "In15.Cu" signal "IN6")
		(34 "In16.Cu" signal "GND7")
		(2 "B.Cu" signal "BOTTOM")
		(9 "F.Adhes" user "F.Adhesive")
		(11 "B.Adhes" user "B.Adhesive")
		(13 "F.Paste" user "Package Geometry/Pastemask Top")
		(15 "B.Paste" user "Package Geometry/Pastemask Bottom")
		(5 "F.SilkS" user "Ref Des/Silkscreen Top")
		(7 "B.SilkS" user "Ref Des/Silkscreen Bottom")
		(1 "F.Mask" user "Board Geometry/Soldermask Top")
		(3 "B.Mask" user "Board Geometry/Soldermask Bottom")
		(17 "Dwgs.User" user "User.Drawings")
		(19 "Cmts.User" user "User.Comments")
		(21 "Eco1.User" user "User.Eco1")
		(23 "Eco2.User" user "User.Eco2")
		(25 "Edge.Cuts" user "Board Geometry/Outline")
		(27 "Margin" user)
		(31 "F.CrtYd" user "Package Geometry/Place Bound Top")
		(29 "B.CrtYd" user "Package Geometry/Place Bound Bottom")
		(35 "F.Fab" user "Ref Des/Assembly Top")
		(33 "B.Fab" user "Ref Des/Assembly Bottom")
	)
	(footprint ""
		(layer "F.Cu")
		(at 314.03544 -63.076328 180)
		(property "Reference" "R4565"
			(at 0 0 180)
			(layer "F.SilkS")
			(hide yes)
			(effects
				(font
					(size 1.27 1.27)
				)
			)
		)
		(property "Value" ""
			(at 0 0 180)
			(layer "F.Fab")
			(effects
				(font
					(size 1.27 1.27)
				)
			)
		)
		(duplicate_pad_numbers_are_jumpers no)
		(fp_line
			(start 0.7874 0.4064)
			(end -0.7874 0.4064)
			(stroke
				(width 0.1524)
				(type default)
			)
			(layer "F.SilkS")
		)
		(fp_line
			(start 0.7874 -0.4064)
			(end 0.7874 0.4064)
			(stroke
				(width 0.1524)
				(type default)
			)
			(layer "F.SilkS")
		)
		(fp_line
			(start -0.7874 0.4064)
			(end -0.7874 -0.4064)
			(stroke
				(width 0.1524)
				(type default)
			)
			(layer "F.SilkS")
		)
		(fp_line
			(start -0.7874 -0.4064)
			(end 0.7874 -0.4064)
			(stroke
				(width 0.1524)
				(type default)
			)
			(layer "F.SilkS")
		)
		(fp_line
			(start 0.67945 0.3048)
			(end 0.120396 0.3048)
			(stroke
				(width 0.1)
				(type default)
			)
			(layer "F.Fab")
		)
		(fp_line
			(start 0.67945 -0.3048)
			(end 0.67945 0.3048)
			(stroke
				(width 0.1)
				(type default)
			)
			(layer "F.Fab")
		)
		(fp_line
			(start 0.12065 -0.2794)
			(end 0.12065 -0.3048)
			(stroke
				(width 0.1)
				(type default)
			)
			(layer "F.Fab")
		)
		(fp_line
			(start 0.12065 -0.3048)
			(end 0.67945 -0.3048)
			(stroke
				(width 0.1)
				(type default)
			)
			(layer "F.Fab")
		)
		(fp_line
			(start 0.120396 0.3048)
			(end 0.120396 0.2794)
			(stroke
				(width 0.1)
				(type default)
			)
			(layer "F.Fab")
		)
		(fp_line
			(start 0.120396 0.2794)
			(end -0.12065 0.2794)
			(stroke
				(width 0.1)
				(type default)
			)
			(layer "F.Fab")
		)
		(fp_line
			(start -0.12065 0.3048)
			(end -0.67945 0.3048)
			(stroke
				(width 0.1)
				(type default)
			)
			(layer "F.Fab")
		)
		(fp_line
			(start -0.12065 0.2794)
			(end -0.12065 0.3048)
			(stroke
				(width 0.1)
				(type default)
			)
			(layer "F.Fab")
		)
		(fp_line
			(start -0.12065 -0.2794)
			(end 0.12065 -0.2794)
			(stroke
				(width 0.1)
				(type default)
			)
			(layer "F.Fab")
		)
		(fp_line
			(start -0.12065 -0.305054)
			(end -0.12065 -0.2794)
			(stroke
				(width 0.1)
				(type default)
			)
			(layer "F.Fab")
		)
		(fp_line
			(start -0.67945 0.3048)
			(end -0.67945 -0.305054)
			(stroke
				(width 0.1)
				(type default)
			)
			(layer "F.Fab")
		)
		(fp_line
			(start -0.67945 -0.305054)
			(end -0.12065 -0.305054)
			(stroke
				(width 0.1)
				(type default)
			)
			(layer "F.Fab")
		)
		(pad "1" smd circle
			(at -0.40005 0 180)
			(size 0 0)
			(layers "F.Cu" "F.Mask" "F.Paste")
			(net "PD_GPP_I_13")
		)
		(pad "2" smd circle
			(at 0.40005 0 180)
			(size 0 0)
			(layers "F.Cu" "F.Mask" "F.Paste")
			(net "GND")
		)
	)
	(footprint ""
		(layer "F.Cu")
		(at 68.2117 -36.294568)
		(property "Reference" "R4092"
			(at 0 0 0)
			(layer "F.SilkS")
			(hide yes)
			(effects
				(font
					(size 1.27 1.27)
				)
			)
		)
		(property "Value" ""
			(at 0 0 0)
			(layer "F.Fab")
			(effects
				(font
					(size 1.27 1.27)
				)
			)
		)
		(duplicate_pad_numbers_are_jumpers no)
		(fp_line
			(start -0.7874 -0.4064)
			(end 0.7874 -0.4064)
			(stroke
				(width 0.1524)
				(type default)
			)
			(layer "F.SilkS")
		)
		(fp_line
			(start -0.7874 0.4064)
			(end -0.7874 -0.4064)
			(stroke
				(width 0.1524)
				(type default)
			)
			(layer "F.SilkS")
		)
		(fp_line
			(start 0.7874 -0.4064)
			(end 0.7874 0.4064)
			(stroke
				(width 0.1524)
				(type default)
			)
			(layer "F.SilkS")
		)
		(fp_line
			(start 0.7874 0.4064)
			(end -0.7874 0.4064)
			(stroke
				(width 0.1524)
				(type default)
			)
			(layer "F.SilkS")
		)
		(fp_line
			(start -0.67945 -0.305054)
			(end -0.12065 -0.305054)
			(stroke
				(width 0.1)
				(type default)
			)
			(layer "F.Fab")
		)
		(fp_line
			(start -0.67945 0.3048)
			(end -0.67945 -0.305054)
			(stroke
				(width 0.1)
				(type default)
			)
			(layer "F.Fab")
		)
		(fp_line
			(start -0.12065 -0.305054)
			(end -0.12065 -0.2794)
			(stroke
				(width 0.1)
				(type default)
			)
			(layer "F.Fab")
		)
		(fp_line
			(start -0.12065 -0.2794)
			(end 0.12065 -0.2794)
			(stroke
				(width 0.1)
				(type default)
			)
			(layer "F.Fab")
		)
		(fp_line
			(start -0.12065 0.2794)
			(end -0.12065 0.3048)
			(stroke
				(width 0.1)
				(type default)
			)
			(layer "F.Fab")
		)
		(fp_line
			(start -0.12065 0.3048)
			(end -0.67945 0.3048)
			(stroke
				(width 0.1)
				(type default)
			)
			(layer "F.Fab")
		)
		(fp_line
			(start 0.120396 0.2794)
			(end -0.12065 0.2794)
			(stroke
				(width 0.1)
				(type default)
			)
			(layer "F.Fab")
		)
		(fp_line
			(start 0.120396 0.3048)
			(end 0.120396 0.2794)
			(stroke
				(width 0.1)
				(type default)
			)
			(layer "F.Fab")
		)
		(fp_line
			(start 0.12065 -0.3048)
			(end 0.67945 -0.3048)
			(stroke
				(width 0.1)
				(type default)
			)
			(layer "F.Fab")
		)
		(fp_line
			(start 0.12065 -0.2794)
			(end 0.12065 -0.3048)
			(stroke
				(width 0.1)
				(type default)
			)
			(layer "F.Fab")
		)
		(fp_line
			(start 0.67945 -0.3048)
			(end 0.67945 0.3048)
			(stroke
				(width 0.1)
				(type default)
			)
			(layer "F.Fab")
		)
		(fp_line
			(start 0.67945 0.3048)
			(end 0.120396 0.3048)
			(stroke
				(width 0.1)
				(type default)
			)
			(layer "F.Fab")
		)
		(pad "1" smd circle
			(at -0.40005 0)
			(size 0 0)
			(layers "F.Cu" "F.Mask" "F.Paste")
			(net "P3V3_AUX")
		)
		(pad "2" smd circle
			(at 0.40005 0)
			(size 0 0)
			(layers "F.Cu" "F.Mask" "F.Paste")
			(net "OCP_V3_2_P3V3_ADC_ALERT_R")
		)
	)
	(footprint ""
		(layer "F.Cu")
		(at 73.6092 -53.546248 180)
		(property "Reference" "PC2142"
			(at 0 0 180)
			(layer "F.SilkS")
			(hide yes)
			(effects
				(font
					(size 1.27 1.27)
				)
			)
		)
		(property "Value" ""
			(at 0 0 180)
			(layer "F.Fab")
			(effects
				(font
					(size 1.27 1.27)
				)
			)
		)
		(duplicate_pad_numbers_are_jumpers no)
		(fp_line
			(start 1.524 0.762)
			(end -1.524 0.762)
			(stroke
				(width 0.1524)
				(type default)
			)
			(layer "F.SilkS")
		)
		(fp_line
			(start 1.524 -0.762)
			(end 1.524 0.762)
			(stroke
				(width 0.1524)
				(type default)
			)
			(layer "F.SilkS")
		)
		(fp_line
			(start -1.524 0.762)
			(end -1.524 -0.762)
			(stroke
				(width 0.1524)
				(type default)
			)
			(layer "F.SilkS")
		)
		(fp_line
			(start -1.524 -0.762)
			(end 1.524 -0.762)
			(stroke
				(width 0.1524)
				(type default)
			)
			(layer "F.SilkS")
		)
		(fp_line
			(start 1.1049 0.724916)
			(end 1.1049 -0.724916)
			(stroke
				(width 0.1)
				(type default)
			)
			(layer "F.Fab")
		)
		(fp_line
			(start 1.1049 -0.724916)
			(end -1.1049 -0.724916)
			(stroke
				(width 0.1)
				(type default)
			)
			(layer "F.Fab")
		)
		(fp_line
			(start -1.1049 0.724916)
			(end 1.1049 0.724916)
			(stroke
				(width 0.1)
				(type default)
			)
			(layer "F.Fab")
		)
		(fp_line
			(start -1.1049 -0.724916)
			(end -1.1049 0.724916)
			(stroke
				(width 0.1)
				(type default)
			)
			(layer "F.Fab")
		)
		(pad "1" smd rect
			(at -0.889 0)
			(size 1.016 1.27)
			(layers "F.Cu" "F.Mask" "F.Paste")
			(net "P3V3_OCP_V3_2_R")
		)
		(pad "2" smd rect
			(at 0.889 0)
			(size 1.016 1.27)
			(layers "F.Cu" "F.Mask" "F.Paste")
			(net "GND")
		)
	)
)
